# BASEBOARD_FAB2 (Tioga Pass) — schematic netlist excerpt (pin names and nets, part order shuffled) for the footprints in the layout excerpt that follows; sources: Cadence DE-HDL packaged netlist, KiCad conversion of Wiwynn_Tioga_Pass_MB.brd

C6U4  CAP  10UF 16V 10% X6S  pkg 0805  page 233 : A = VR_FET_SW_P12V_STBY_PVPP_GHJ ; B = GND
C5G103  CAP_A  22.0UF 4V 20% X6S  pkg 0603V  page 243 : A = PVDDQ_KLM ; B = GND

(kicad_pcb
	(version 20260206)
	(generator "pcbnew")
	(generator_version "10.0")
	(general
		(thickness 1.6)
		(legacy_teardrops no)
	)
	(paper "A4")
	(title_block
		(title "Wiwynn_Tioga_Pass_MB.brd")
		(comment 1 "Tioga Pass / footprints 2528-2530 of 4770")
	)
	(layers
		(0 "F.Cu" signal "TOP")
		(4 "In1.Cu" signal "L2GND")
		(6 "In2.Cu" signal "L3")
		(8 "In3.Cu" signal "L4GND")
		(10 "In4.Cu" signal "L5")
		(12 "In5.Cu" signal "L6GND")
		(14 "In6.Cu" signal "L7VCC")
		(16 "In7.Cu" signal "L8VCC")
		(18 "In8.Cu" signal "L9GND")
		(20 "In9.Cu" signal "L10")
		(22 "In10.Cu" signal "L11GND")
		(24 "In11.Cu" signal "L12")
		(26 "In12.Cu" signal "L13GND")
		(2 "B.Cu" signal "BOTTOM")
		(9 "F.Adhes" user "F.Adhesive")
		(11 "B.Adhes" user "B.Adhesive")
		(13 "F.Paste" user "Package Geometry/Pastemask Top")
		(15 "B.Paste" user "Package Geometry/Pastemask Bottom")
		(5 "F.SilkS" user "Ref Des/Silkscreen Top")
		(7 "B.SilkS" user "Ref Des/Silkscreen Bottom")
		(1 "F.Mask" user "Board Geometry/Soldermask Top")
		(3 "B.Mask" user "Board Geometry/Soldermask Bottom")
		(17 "Dwgs.User" user "User.Drawings")
		(19 "Cmts.User" user "User.Comments")
		(21 "Eco1.User" user "User.Eco1")
		(23 "Eco2.User" user "User.Eco2")
		(25 "Edge.Cuts" user "Board Geometry/Outline")
		(27 "Margin" user)
		(31 "F.CrtYd" user "Package Geometry/Place Bound Top")
		(29 "B.CrtYd" user "Package Geometry/Place Bound Bottom")
		(35 "F.Fab" user "Ref Des/Assembly Top")
		(33 "B.Fab" user "Ref Des/Assembly Bottom")
	)
	(footprint ""
		(layer "B.Cu")
		(at 308.768496 -33.874202)
		(property "Reference" ""
			(at 0 0 0)
			(layer "B.SilkS")
			(hide yes)
			(effects
				(font
					(size 1.27 1.27)
				)
				(justify mirror)
			)
		)
		(property "Value" ""
			(at 0 0 0)
			(layer "B.Fab")
			(effects
				(font
					(size 1.27 1.27)
				)
				(justify mirror)
			)
		)
		(duplicate_pad_numbers_are_jumpers no)
		(fp_poly
			(pts
				(arc
					(start 2.032 0)
					(mid -2.032 0)
					(end 2.032 0)
				)
			)
			(stroke
				(width 0)
				(type default)
			)
			(fill no)
			(layer "B.CrtYd")
		)
		(pad "1" smd circle
			(at 0 0 180)
			(size 1.016 1.016)
			(layers "B.Cu" "B.Mask" "B.Paste")
			(net "Net_398")
		)
		(zone
			(layers "F.Cu" "B.Cu" "In1.Cu" "In2.Cu" "In3.Cu" "In4.Cu" "In5.Cu" "In6.Cu"
				"In7.Cu" "In8.Cu" "In9.Cu" "In10.Cu" "In11.Cu" "In12.Cu"
			)
			(hatch none 0.5)
			(connect_pads
				(clearance 0)
			)
			(min_thickness 0.25)
			(keepout
				(tracks allowed)
				(vias not_allowed)
				(pads allowed)
				(copperpour not_allowed)
				(footprints allowed)
			)
			(placement
				(enabled no)
				(sheetname "")
			)
			(fill
				(thermal_gap 0.5)
				(thermal_bridge_width 0.5)
				(island_removal_mode 0)
			)
			(polygon
				(pts
					(arc
						(start 310.292496 -33.874202)
						(mid 307.244496 -33.874202)
						(end 310.292496 -33.874202)
					)
				)
			)
		)
		(zone
			(layer "B.Cu")
			(hatch none 0.5)
			(connect_pads
				(clearance 0)
			)
			(min_thickness 0.25)
			(keepout
				(tracks not_allowed)
				(vias allowed)
				(pads allowed)
				(copperpour not_allowed)
				(footprints allowed)
			)
			(placement
				(enabled no)
				(sheetname "")
			)
			(fill
				(thermal_gap 0.5)
				(thermal_bridge_width 0.5)
				(island_removal_mode 0)
			)
			(polygon
				(pts
					(arc
						(start 310.292496 -33.874202)
						(mid 307.244496 -33.874202)
						(end 310.292496 -33.874202)
					)
				)
			)
		)
	)
	(footprint ""
		(layer "B.Cu")
		(at 183.261 -13.589 180)
		(property "Reference" "C6U4"
			(at 0 0 0)
			(layer "B.SilkS")
			(hide yes)
			(effects
				(font
					(size 1.27 1.27)
				)
				(justify mirror)
			)
		)
		(property "Value" ""
			(at 0 0 0)
			(layer "B.Fab")
			(effects
				(font
					(size 1.27 1.27)
				)
				(justify mirror)
			)
		)
		(duplicate_pad_numbers_are_jumpers no)
		(fp_poly
			(pts
				(xy 0.7239 -0.2159) (xy -0.7239 -0.2159) (xy -0.7239 1.9939) (xy 0.7239 1.9939)
			)
			(stroke
				(width 0)
				(type default)
			)
			(fill no)
			(layer "B.CrtYd")
		)
		(fp_line
			(start 0.7239 1.9939)
			(end -0.7239 1.9939)
			(stroke
				(width 0.1)
				(type default)
			)
			(layer "B.Fab")
		)
		(fp_line
			(start 0.7239 -0.2159)
			(end 0.7239 1.9939)
			(stroke
				(width 0.1)
				(type default)
			)
			(layer "B.Fab")
		)
		(fp_line
			(start -0.7239 1.9939)
			(end -0.7239 -0.2159)
			(stroke
				(width 0.1)
				(type default)
			)
			(layer "B.Fab")
		)
		(fp_line
			(start -0.7239 -0.2159)
			(end 0.7239 -0.2159)
			(stroke
				(width 0.1)
				(type default)
			)
			(layer "B.Fab")
		)
		(pad "1" smd rect
			(at 0 0)
			(size 1.27 1.016)
			(layers "B.Cu" "B.Mask" "B.Paste")
			(net "VR_FET_SW_P12V_STBY_PVPP_GHJ")
		)
		(pad "2" smd rect
			(at 0 1.778)
			(size 1.27 1.016)
			(layers "B.Cu" "B.Mask" "B.Paste")
			(net "GND")
		)
		(zone
			(layer "B.Cu")
			(hatch none 0.5)
			(connect_pads
				(clearance 0)
			)
			(min_thickness 0.25)
			(keepout
				(tracks not_allowed)
				(vias allowed)
				(pads allowed)
				(copperpour not_allowed)
				(footprints allowed)
			)
			(placement
				(enabled no)
				(sheetname "")
			)
			(fill
				(thermal_gap 0.5)
				(thermal_bridge_width 0.5)
				(island_removal_mode 0)
			)
			(polygon
				(pts
					(xy 182.626 -14.097) (xy 183.896 -14.097) (xy 183.896 -14.859) (xy 182.626 -14.859)
				)
			)
		)
	)
	(footprint ""
		(layer "B.Cu")
		(at 104.5591 -149.8092 90)
		(property "Reference" "C5G103"
			(at -1.14681 0.76708 180)
			(unlocked yes)
			(layer "B.SilkS")
			(effects
				(font
					(size 0.7874 0.5842)
					(thickness 0.1524)
				)
				(justify mirror)
			)
		)
		(property "Value" ""
			(at 0 0 90)
			(layer "B.Fab")
			(effects
				(font
					(size 1.27 1.27)
				)
				(justify mirror)
			)
		)
		(duplicate_pad_numbers_are_jumpers no)
		(fp_rect
			(start -0.4953 -0.2032)
			(end 0.4953 1.6002)
			(stroke
				(width 0)
				(type default)
			)
			(fill no)
			(layer "B.CrtYd")
		)
		(fp_line
			(start 0.4953 -0.2032)
			(end -0.4953 -0.2032)
			(stroke
				(width 0.1)
				(type default)
			)
			(layer "B.Fab")
		)
		(fp_line
			(start -0.4953 -0.2032)
			(end -0.4953 1.6002)
			(stroke
				(width 0.1)
				(type default)
			)
			(layer "B.Fab")
		)
		(fp_line
			(start 0.4953 1.6002)
			(end 0.4953 -0.2032)
			(stroke
				(width 0.1)
				(type default)
			)
			(layer "B.Fab")
		)
		(fp_line
			(start -0.4953 1.6002)
			(end 0.4953 1.6002)
			(stroke
				(width 0.1)
				(type default)
			)
			(layer "B.Fab")
		)
		(pad "1" smd rect
			(at 0 0 270)
			(size 0.762 0.889)
			(layers "B.Cu" "B.Mask" "B.Paste")
			(net "PVDDQ_KLM")
		)
		(pad "2" smd rect
			(at 0 1.397 270)
			(size 0.762 0.889)
			(layers "B.Cu" "B.Mask" "B.Paste")
			(net "GND")
		)
		(zone
			(layer "B.Cu")
			(hatch none 0.5)
			(connect_pads
				(clearance 0)
			)
			(min_thickness 0.25)
			(keepout
				(tracks not_allowed)
				(vias allowed)
				(pads allowed)
				(copperpour not_allowed)
				(footprints allowed)
			)
			(placement
				(enabled no)
				(sheetname "")
			)
			(fill
				(thermal_gap 0.5)
				(thermal_bridge_width 0.5)
				(island_removal_mode 0)
			)
			(polygon
				(pts
					(xy 105.0036 -149.4282) (xy 105.5116 -149.4282) (xy 105.5116 -150.1902) (xy 105.0036 -150.1902)
				)
			)
		)
	)
)
